(kicad_pcb
	(version 20241229)
	(generator "pcbnew")
	(generator_version "9.0")
	(general
		(thickness 1.62)
		(legacy_teardrops no)
	)
	(paper "A4")
	(title_block
		(title "OCuLink to 10GbE adapter")
		(date "2026-02-23")
		(rev "1.1.0")
		(company "Antmicro Ltd")
		(comment 1 "www.antmicro.com")
		(comment 9 "footprints 168-172 of 510")
	)
	(layers
		(0 "F.Cu" signal)
		(4 "In1.Cu" signal)
		(6 "In2.Cu" signal)
		(8 "In3.Cu" signal)
		(10 "In4.Cu" signal)
		(12 "In5.Cu" signal)
		(14 "In6.Cu" signal)
		(2 "B.Cu" signal)
		(9 "F.Adhes" user "F.Adhesive")
		(11 "B.Adhes" user "B.Adhesive")
		(13 "F.Paste" user)
		(15 "B.Paste" user)
		(5 "F.SilkS" user "F.Silkscreen")
		(7 "B.SilkS" user "B.Silkscreen")
		(1 "F.Mask" user)
		(3 "B.Mask" user)
		(17 "Dwgs.User" user "User.Drawings")
		(19 "Cmts.User" user "User.Comments")
		(21 "Eco1.User" user "User.Eco1")
		(23 "Eco2.User" user "User.Eco2")
		(25 "Edge.Cuts" user)
		(27 "Margin" user)
		(31 "F.CrtYd" user "F.Courtyard")
		(29 "B.CrtYd" user "B.Courtyard")
		(35 "F.Fab" user)
		(33 "B.Fab" user)
	)
	(footprint "antmicro-footprints:C_0402_1005Metric"
		(layer "F.Cu")
		(at 67.27 110.35 180)
		(descr "Capacitor SMD 0402")
		(tags "capacitor SMD 0402")
		(property "Reference" "C162"
			(at 0.69 0.31 0)
			(layer "F.SilkS")
			(effects
				(font
					(size 0.7 0.7)
					(thickness 0.15)
				)
				(justify right top)
			)
		)
		(property "Value" "C_100n_0402"
			(at -1.022927 2.155213 0)
			(layer "F.Fab")
			(hide yes)
			(effects
				(font
					(size 0.7 0.7)
					(thickness 0.15)
				)
				(justify right top)
			)
		)
		(property "Datasheet" "https://www.murata.com/products/productdetail?partno=GRM155R61H104KE14%23"
			(at 0 0 0)
			(layer "F.Fab")
			(hide yes)
			(effects
				(font
					(size 1.27 1.27)
					(thickness 0.15)
				)
			)
		)
		(property "Description" "SMD Multilayer Ceramic Capacitor, 0.1 µF, 50 V, 0402 [1005 Metric], ± 10%, X5R, GRM Series"
			(at 0 0 0)
			(layer "F.Fab")
			(hide yes)
			(effects
				(font
					(size 1.27 1.27)
					(thickness 0.15)
				)
			)
		)
		(property "MPN" "GRM155R61H104KE14D"
			(at 0 0 180)
			(unlocked yes)
			(layer "F.Fab")
			(hide yes)
			(effects
				(font
					(size 1 1)
					(thickness 0.15)
				)
			)
		)
		(property "Val" "100n"
			(at 0 0 180)
			(unlocked yes)
			(layer "F.Fab")
			(hide yes)
			(effects
				(font
					(size 1 1)
					(thickness 0.15)
				)
			)
		)
		(property "Voltage" "50V"
			(at 0 0 180)
			(unlocked yes)
			(layer "F.Fab")
			(hide yes)
			(effects
				(font
					(size 1 1)
					(thickness 0.15)
				)
			)
		)
		(property "Dielectric" "X5R"
			(at 0 0 180)
			(unlocked yes)
			(layer "F.Fab")
			(hide yes)
			(effects
				(font
					(size 1 1)
					(thickness 0.15)
				)
			)
		)
		(property "Manufacturer" "Murata"
			(at 0 0 180)
			(unlocked yes)
			(layer "F.Fab")
			(hide yes)
			(effects
				(font
					(size 1 1)
					(thickness 0.15)
				)
			)
		)
		(property "License" "Apache-2.0"
			(at 0 0 180)
			(unlocked yes)
			(layer "F.Fab")
			(hide yes)
			(effects
				(font
					(size 1 1)
					(thickness 0.15)
				)
			)
		)
		(property "Author" "Antmicro"
			(at 0 0 180)
			(unlocked yes)
			(layer "F.Fab")
			(hide yes)
			(effects
				(font
					(size 1 1)
					(thickness 0.15)
				)
			)
		)
		(sheetname "/X710-AT2 power/")
		(sheetfile "x710-at2-power.kicad_sch")
		(attr smd)
		(fp_rect
			(start -0.925 -0.47)
			(end 0.925 0.47)
			(stroke
				(width 0.05)
				(type default)
			)
			(fill no)
			(layer "F.CrtYd")
		)
		(fp_line
			(start 0.504 0.248)
			(end -0.494 0.248)
			(stroke
				(width 0.15)
				(type solid)
			)
			(layer "F.Fab")
		)
		(fp_line
			(start 0.504 -0.25)
			(end 0.504 0.248)
			(stroke
				(width 0.15)
				(type solid)
			)
			(layer "F.Fab")
		)
		(fp_line
			(start -0.494 0.248)
			(end -0.494 -0.25)
			(stroke
				(width 0.15)
				(type solid)
			)
			(layer "F.Fab")
		)
		(fp_line
			(start -0.494 -0.25)
			(end 0.504 -0.25)
			(stroke
				(width 0.15)
				(type solid)
			)
			(layer "F.Fab")
		)
		(pad "1" smd roundrect
			(at -0.48 0 180)
			(size 0.59 0.64)
			(layers "F.Cu" "F.Mask" "F.Paste")
			(roundrect_rratio 0.25)
			(net 28 "GND")
			(pintype "passive")
		)
		(pad "2" smd roundrect
			(at 0.48 0 180)
			(size 0.59 0.64)
			(layers "F.Cu" "F.Mask" "F.Paste")
			(roundrect_rratio 0.25)
			(net 302 "+1V0")
			(pintype "passive")
		)
	)
	(footprint "antmicro-footprints:MP_Pad6mm_Drill3.2mm"
		(layer "F.Cu")
		(at 62.975 121.995)
		(property "Reference" "MP7"
			(at 0 -3.2 0)
			(layer "F.SilkS")
			(hide yes)
			(effects
				(font
					(size 0.7 0.7)
					(thickness 0.15)
				)
				(justify left bottom)
			)
		)
		(property "Value" "MP_Pad6mm_Drill3.2mm"
			(at 0 3.9 0)
			(layer "F.Fab")
			(hide yes)
			(effects
				(font
					(size 0.7 0.7)
					(thickness 0.15)
				)
				(justify left bottom)
			)
		)
		(property "Description" "Mechanical part"
			(at 0 0 0)
			(layer "F.Fab")
			(hide yes)
			(effects
				(font
					(size 1.27 1.27)
					(thickness 0.15)
				)
			)
		)
		(property "Author" "Antmicro"
			(at 0 0 0)
			(unlocked yes)
			(layer "F.Fab")
			(hide yes)
			(effects
				(font
					(size 1 1)
					(thickness 0.15)
				)
			)
		)
		(property "License" "Apache-2.0"
			(at 0 0 0)
			(unlocked yes)
			(layer "F.Fab")
			(hide yes)
			(effects
				(font
					(size 1 1)
					(thickness 0.15)
				)
			)
		)
		(sheetname "/")
		(sheetfile "oculink-to-10gbe-adapter.kicad_sch")
		(attr exclude_from_pos_files exclude_from_bom)
		(fp_circle
			(center 0 0)
			(end 3.25 0)
			(stroke
				(width 0.05)
				(type default)
			)
			(fill no)
			(layer "F.CrtYd")
		)
		(fp_text user "License: Apache-2.0"
			(at -0.178 8.425 0)
			(layer "F.Fab")
			(effects
				(font
					(size 0.7 0.7)
					(thickness 0.15)
				)
				(justify left bottom)
			)
		)
		(fp_text user "${REFERENCE}"
			(at -0.178 6.025 0)
			(layer "F.Fab")
			(effects
				(font
					(size 0.7 0.7)
					(thickness 0.15)
				)
				(justify left bottom)
			)
		)
		(fp_text user "Author: Antmicro"
			(at -0.178 7.225 0)
			(layer "F.Fab")
			(effects
				(font
					(size 0.7 0.7)
					(thickness 0.15)
				)
				(justify left bottom)
			)
		)
		(pad "1" thru_hole circle
			(at 0 0)
			(size 6 6)
			(drill 3.2)
			(layers "*.Cu" "*.Mask")
			(remove_unused_layers no)
			(net 28 "GND")
			(pintype "passive")
		)
	)
	(footprint "antmicro-footprints:R_0402_1005Metric"
		(layer "F.Cu")
		(at 57.15 118.05 180)
		(descr "Resistor SMD 0402")
		(tags "resistor SMD 0402")
		(property "Reference" "R148"
			(at -1.45 -0.772697 0)
			(layer "F.SilkS")
			(effects
				(font
					(size 0.7 0.7)
					(thickness 0.15)
				)
				(justify right top)
			)
		)
		(property "Value" "R_1k_0402"
			(at -1.011843 1.772046 0)
			(layer "F.Fab")
			(hide yes)
			(effects
				(font
					(size 0.7 0.7)
					(thickness 0.15)
				)
				(justify right top)
			)
		)
		(property "Datasheet" "https://www.bourns.com/docs/product-datasheets/cr.pdf"
			(at 0 0 0)
			(layer "F.Fab")
			(hide yes)
			(effects
				(font
					(size 1.27 1.27)
					(thickness 0.15)
				)
			)
		)
		(property "Description" "SMD Chip Resistor, 1 kohm, ± 1%, 63 mW, 0402 [1005 Metric], Thick Film, General Purpose"
			(at 0 0 0)
			(layer "F.Fab")
			(hide yes)
			(effects
				(font
					(size 1.27 1.27)
					(thickness 0.15)
				)
			)
		)
		(property "MPN" "CR0402-FX-1001GLF"
			(at 0 0 180)
			(unlocked yes)
			(layer "F.Fab")
			(hide yes)
			(effects
				(font
					(size 1 1)
					(thickness 0.15)
				)
			)
		)
		(property "Manufacturer" "Bourns"
			(at 0 0 180)
			(unlocked yes)
			(layer "F.Fab")
			(hide yes)
			(effects
				(font
					(size 1 1)
					(thickness 0.15)
				)
			)
		)
		(property "License" "Apache-2.0"
			(at 0 0 180)
			(unlocked yes)
			(layer "F.Fab")
			(hide yes)
			(effects
				(font
					(size 1 1)
					(thickness 0.15)
				)
			)
		)
		(property "Author" "Antmicro"
			(at 0 0 180)
			(unlocked yes)
			(layer "F.Fab")
			(hide yes)
			(effects
				(font
					(size 1 1)
					(thickness 0.15)
				)
			)
		)
		(property "Val" "1k"
			(at 0 0 180)
			(unlocked yes)
			(layer "F.Fab")
			(hide yes)
			(effects
				(font
					(size 1 1)
					(thickness 0.15)
				)
			)
		)
		(property "Tolerance" "1%"
			(at 0 0 180)
			(unlocked yes)
			(layer "F.Fab")
			(hide yes)
			(effects
				(font
					(size 1 1)
					(thickness 0.15)
				)
			)
		)
		(sheetname "/Power/")
		(sheetfile "power.kicad_sch")
		(attr smd)
		(fp_poly
			(pts
				(xy -0.925 -0.47) (xy 0.925 -0.47) (xy 0.925 0.47) (xy -0.925 0.47)
			)
			(stroke
				(width 0.05)
				(type default)
			)
			(fill no)
			(layer "F.CrtYd")
		)
		(fp_poly
			(pts
				(xy -0.5 -0.25) (xy 0.5 -0.25) (xy 0.5 0.25) (xy -0.5 0.25)
			)
			(stroke
				(width 0.15)
				(type solid)
			)
			(fill no)
			(layer "F.Fab")
		)
		(pad "1" smd roundrect
			(at -0.48 0 180)
			(size 0.59 0.64)
			(layers "F.Cu" "F.Mask" "F.Paste")
			(roundrect_rratio 0.25)
			(net 419 "Net-(Q9-C)")
			(pintype "passive")
		)
		(pad "2" smd roundrect
			(at 0.48 0 180)
			(size 0.59 0.64)
			(layers "F.Cu" "F.Mask" "F.Paste")
			(roundrect_rratio 0.25)
			(net 414 "Net-(D20-C)")
			(pintype "passive")
		)
	)
	(footprint "antmicro-footprints:R_0402_1005Metric"
		(layer "F.Cu")
		(at 79.96 58.9)
		(descr "Resistor SMD 0402")
		(tags "resistor SMD 0402")
		(property "Reference" "R20"
			(at 1.09 1.55 0)
			(layer "F.SilkS")
			(effects
				(font
					(size 0.7 0.7)
					(thickness 0.15)
				)
				(justify right top)
			)
		)
		(property "Value" "R_1k_0402"
			(at -1.011843 1.772046 0)
			(layer "F.Fab")
			(hide yes)
			(effects
				(font
					(size 0.7 0.7)
					(thickness 0.15)
				)
				(justify left bottom)
			)
		)
		(property "Datasheet" "https://www.bourns.com/docs/product-datasheets/cr.pdf"
			(at 0 0 0)
			(layer "F.Fab")
			(hide yes)
			(effects
				(font
					(size 1.27 1.27)
					(thickness 0.15)
				)
			)
		)
		(property "Description" "SMD Chip Resistor, 1 kohm, ± 1%, 63 mW, 0402 [1005 Metric], Thick Film, General Purpose"
			(at 0 0 0)
			(layer "F.Fab")
			(hide yes)
			(effects
				(font
					(size 1.27 1.27)
					(thickness 0.15)
				)
			)
		)
		(property "MPN" "CR0402-FX-1001GLF"
			(at 0 0 0)
			(unlocked yes)
			(layer "F.Fab")
			(hide yes)
			(effects
				(font
					(size 1 1)
					(thickness 0.15)
				)
			)
		)
		(property "Manufacturer" "Bourns"
			(at 0 0 0)
			(unlocked yes)
			(layer "F.Fab")
			(hide yes)
			(effects
				(font
					(size 1 1)
					(thickness 0.15)
				)
			)
		)
		(property "License" "Apache-2.0"
			(at 0 0 0)
			(unlocked yes)
			(layer "F.Fab")
			(hide yes)
			(effects
				(font
					(size 1 1)
					(thickness 0.15)
				)
			)
		)
		(property "Author" "Antmicro"
			(at 0 0 0)
			(unlocked yes)
			(layer "F.Fab")
			(hide yes)
			(effects
				(font
					(size 1 1)
					(thickness 0.15)
				)
			)
		)
		(property "Val" "1k"
			(at 0 0 0)
			(unlocked yes)
			(layer "F.Fab")
			(hide yes)
			(effects
				(font
					(size 1 1)
					(thickness 0.15)
				)
			)
		)
		(property "Tolerance" "1%"
			(at 0 0 0)
			(unlocked yes)
			(layer "F.Fab")
			(hide yes)
			(effects
				(font
					(size 1 1)
					(thickness 0.15)
				)
			)
		)
		(sheetname "/Power/")
		(sheetfile "power.kicad_sch")
		(attr smd)
		(fp_rect
			(start -0.925 -0.47)
			(end 0.925 0.47)
			(stroke
				(width 0.05)
				(type default)
			)
			(fill no)
			(layer "F.CrtYd")
		)
		(fp_rect
			(start -0.5 -0.25)
			(end 0.5 0.25)
			(stroke
				(width 0.15)
				(type solid)
			)
			(fill no)
			(layer "F.Fab")
		)
		(pad "1" smd roundrect
			(at -0.48 0)
			(size 0.59 0.64)
			(layers "F.Cu" "F.Mask" "F.Paste")
			(roundrect_rratio 0.25)
			(net 75 "Net-(D3-A)")
			(pintype "passive")
		)
		(pad "2" smd roundrect
			(at 0.48 0)
			(size 0.59 0.64)
			(layers "F.Cu" "F.Mask" "F.Paste")
			(roundrect_rratio 0.25)
			(net 351 "/Power/+5V_USB")
			(pintype "passive")
		)
	)
	(footprint "antmicro-footprints:RJ45_JTH-0024NL"
		(layer "F.Cu")
		(at 101.05 132.39 180)
		(property "Reference" "J6"
			(at -2.455 4.45 0)
			(unlocked yes)
			(layer "F.SilkS")
			(effects
				(font
					(size 0.7 0.7)
					(thickness 0.15)
				)
				(justify left bottom)
			)
		)
		(property "Value" "Bus_RJ45_JTH-0024NL"
			(at 5.06 1 180)
			(unlocked yes)
			(layer "F.Fab")
			(hide yes)
			(effects
				(font
					(size 0.7 0.7)
					(thickness 0.15)
				)
				(justify left bottom)
			)
		)
		(property "Datasheet" "https://www.mouser.com/datasheet/2/447/JTH_0024NL-3072047.pdf"
			(at 0 0 0)
			(layer "F.Fab")
			(hide yes)
			(effects
				(font
					(size 1.27 1.27)
					(thickness 0.15)
				)
			)
		)
		(property "Description" "Modular Connectors / Ethernet Connectors 1X1 TAB DOWN W/LED'S ETHERNET (NON PoE)"
			(at 0 0 0)
			(layer "F.Fab")
			(hide yes)
			(effects
				(font
					(size 1.27 1.27)
					(thickness 0.15)
				)
			)
		)
		(property "MPN" "JTH-0024NL"
			(at 0 0 180)
			(unlocked yes)
			(layer "F.Fab")
			(hide yes)
			(effects
				(font
					(size 1 1)
					(thickness 0.15)
				)
			)
		)
		(property "Manufacturer" "Pulse Electronics"
			(at 0 0 180)
			(unlocked yes)
			(layer "F.Fab")
			(hide yes)
			(effects
				(font
					(size 1 1)
					(thickness 0.15)
				)
			)
		)
		(property "Author" "Antmicro"
			(at 0 0 180)
			(unlocked yes)
			(layer "F.Fab")
			(hide yes)
			(effects
				(font
					(size 1 1)
					(thickness 0.15)
				)
			)
		)
		(property "License" "Apache-2.0"
			(at 0 0 180)
			(unlocked yes)
			(layer "F.Fab")
			(hide yes)
			(effects
				(font
					(size 1 1)
					(thickness 0.15)
				)
			)
		)
		(property ki_fp_filters "CONN18_5-2337992-8_TEC")
		(sheetname "/2xRJ45/")
		(sheetfile "2xrj45.kicad_sch")
		(attr through_hole)
		(fp_line
			(start 14 4)
			(end 14 -5.25)
			(stroke
				(width 0.1)
				(type default)
			)
			(layer "F.SilkS")
		)
		(fp_line
			(start -3.75 4)
			(end 14 4)
			(stroke
				(width 0.1)
				(type default)
			)
			(layer "F.SilkS")
		)
		(fp_line
			(start -3.75 -5.25)
			(end -3.75 4)
			(stroke
				(width 0.1)
				(type default)
			)
			(layer "F.SilkS")
		)
		(fp_rect
			(start -5.4 -20.72)
			(end 15.58 4.45)
			(stroke
				(width 0.05)
				(type solid)
			)
			(fill no)
			(layer "F.CrtYd")
		)
		(fp_text user "Author: Antmicro"
			(at -5.75 8.85 180)
			(layer "F.Fab")
			(effects
				(font
					(size 0.7 0.7)
					(thickness 0.15)
				)
				(justify left bottom)
			)
		)
		(fp_text user "${REFERENCE}"
			(at -5.75 6.45 180)
			(unlocked yes)
			(layer "F.Fab")
			(effects
				(font
					(size 0.7 0.7)
					(thickness 0.15)
				)
				(justify left bottom)
			)
		)
		(fp_text user "License: Apache-2.0"
			(at -5.75 7.65 180)
			(layer "F.Fab")
			(effects
				(font
					(size 0.7 0.7)
					(thickness 0.15)
				)
				(justify left bottom)
			)
		)
		(pad "" np_thru_hole circle
			(at 0.245 -6.6 180)
			(size 3.2 3.2)
			(drill 3.2)
			(layers "*.Cu" "*.Mask")
		)
		(pad "" np_thru_hole circle
			(at 9.895 -6.6 180)
			(size 3.2 3.2)
			(drill 3.2)
			(layers "*.Cu" "*.Mask")
		)
		(pad "1" thru_hole circle
			(at 0 0 180)
			(size 1.39 1.39)
			(drill 0.89)
			(layers "*.Cu" "*.Mask")
			(remove_unused_layers no)
			(net 300 "/2xRJ45/P1_CT")
			(pinfunction "CT3")
			(pintype "bidirectional")
		)
		(pad "2" thru_hole circle
			(at 2.03 0 180)
			(size 1.39 1.39)
			(drill 0.89)
			(layers "*.Cu" "*.Mask")
			(remove_unused_layers no)
			(net 60 "/2xRJ45/Ethernet_P1.D2-")
			(pinfunction "T2-")
			(pintype "bidirectional")
		)
		(pad "3" thru_hole circle
			(at 4.06 0 180)
			(size 1.39 1.39)
			(drill 0.89)
			(layers "*.Cu" "*.Mask")
			(remove_unused_layers no)
			(net 62 "/2xRJ45/Ethernet_P1.D2+")
			(pinfunction "T2+")
			(pintype "bidirectional")
		)
		(pad "4" thru_hole circle
			(at 6.09 0 180)
			(size 1.39 1.39)
			(drill 0.89)
			(layers "*.Cu" "*.Mask")
			(remove_unused_layers no)
			(net 63 "/2xRJ45/Ethernet_P1.D3+")
			(pinfunction "T3+")
			(pintype "bidirectional")
		)
		(pad "5" thru_hole circle
			(at 8.12 0 180)
			(size 1.39 1.39)
			(drill 0.89)
			(layers "*.Cu" "*.Mask")
			(remove_unused_layers no)
			(net 65 "/2xRJ45/Ethernet_P1.D3-")
			(pinfunction "T3-")
			(pintype "bidirectional")
		)
		(pad "6" thru_hole circle
			(at 10.15 0 180)
			(size 1.39 1.39)
			(drill 0.89)
			(layers "*.Cu" "*.Mask")
			(remove_unused_layers no)
			(net 300 "/2xRJ45/P1_CT")
			(pinfunction "CT2")
			(pintype "bidirectional")
		)
		(pad "7" thru_hole circle
			(at -1.02 2.54 180)
			(size 1.39 1.39)
			(drill 0.89)
			(layers "*.Cu" "*.Mask")
			(remove_unused_layers no)
			(net 300 "/2xRJ45/P1_CT")
			(pinfunction "CT4")
			(pintype "bidirectional")
		)
		(pad "8" thru_hole circle
			(at 1.01 2.54 180)
			(size 1.39 1.39)
			(drill 0.89)
			(layers "*.Cu" "*.Mask")
			(remove_unused_layers no)
			(net 69 "/2xRJ45/Ethernet_P1.D1+")
			(pinfunction "T1+")
			(pintype "bidirectional")
		)
		(pad "9" thru_hole circle
			(at 3.04 2.54 180)
			(size 1.39 1.39)
			(drill 0.89)
			(layers "*.Cu" "*.Mask")
			(remove_unused_layers no)
			(net 59 "/2xRJ45/Ethernet_P1.D1-")
			(pinfunction "T1-")
			(pintype "bidirectional")
		)
		(pad "10" thru_hole circle
			(at 7.11 2.54 180)
			(size 1.39 1.39)
			(drill 0.89)
			(layers "*.Cu" "*.Mask")
			(remove_unused_layers no)
			(net 68 "/2xRJ45/Ethernet_P1.D4-")
			(pinfunction "T4-")
			(pintype "bidirectional")
		)
		(pad "11" thru_hole circle
			(at 9.14 2.54 180)
			(size 1.39 1.39)
			(drill 0.89)
			(layers "*.Cu" "*.Mask")
			(remove_unused_layers no)
			(net 67 "/2xRJ45/Ethernet_P1.D4+")
			(pinfunction "T4+")
			(pintype "bidirectional")
		)
		(pad "12" thru_hole circle
			(at 11.17 2.54 180)
			(size 1.39 1.39)
			(drill 0.89)
			(layers "*.Cu" "*.Mask")
			(remove_unused_layers no)
			(net 300 "/2xRJ45/P1_CT")
			(pinfunction "CT1")
			(pintype "bidirectional")
		)
		(pad "13" thru_hole circle
			(at 12.59 -12.95 180)
			(size 1.77 1.77)
			(drill 1.27)
			(layers "*.Cu" "*.Mask")
			(remove_unused_layers no)
			(net 66 "Net-(J6-LED_GRN-)")
			(pinfunction "LED_GRN-")
			(pintype "passive")
		)
		(pad "14" thru_hole circle
			(at 12.59 -15.49 180)
			(size 1.77 1.77)
			(drill 1.27)
			(layers "*.Cu" "*.Mask")
			(remove_unused_layers no)
			(net 7 "+3V3")
			(pinfunction "LED_GRN+")
			(pintype "passive")
		)
		(pad "15" thru_hole circle
			(at -2.45 -10.41 180)
			(size 1.77 1.77)
			(drill 1.27)
			(layers "*.Cu" "*.Mask")
			(remove_unused_layers no)
			(net 61 "Net-(J6-LED_YG_Y-)")
			(pinfunction "LED_YG_Y-")
			(pintype "passive")
		)
		(pad "16" thru_hole circle
			(at -2.45 -12.95 180)
			(size 1.77 1.77)
			(drill 1.27)
			(layers "*.Cu" "*.Mask")
			(remove_unused_layers no)
			(net 7 "+3V3")
			(pinfunction "LED_COM+")
			(pintype "passive")
		)
		(pad "17" thru_hole circle
			(at -2.45 -15.49 180)
			(size 1.77 1.77)
			(drill 1.27)
			(layers "*.Cu" "*.Mask")
			(remove_unused_layers no)
			(net 64 "Net-(J6-LED_YG_G-)")
			(pinfunction "LED_YG_G-")
			(pintype "passive")
		)
		(pad "SH" thru_hole circle
			(at -3.72 -6.6 180)
			(size 2.07 2.07)
			(drill 1.57)
			(layers "*.Cu" "*.Mask")
			(remove_unused_layers no)
			(net 28 "GND")
			(pinfunction "SHIELD")
			(pintype "passive")
		)
		(pad "SH" thru_hole circle
			(at 13.86 -6.6 180)
			(size 2.07 2.07)
			(drill 1.57)
			(layers "*.Cu" "*.Mask")
			(remove_unused_layers no)
			(net 28 "GND")
			(pinfunction "SHIELD")
			(pintype "passive")
		)
	)
)
